(kicad_pcb
	(version 20260206)
	(generator "pcbnew")
	(generator_version "10.0")
	(general
		(thickness 1.6)
		(legacy_teardrops no)
	)
	(paper "A4")
	(title_block
		(title "01162023_DA0F0TEBIF0_F0T_Expander_BD_F_brd_V02_OCP.brd")
		(comment 1 "Grand Teton / footprints 3364-3370 of 9728")
	)
	(layers
		(0 "F.Cu" signal "TOP")
		(4 "In1.Cu" signal "GND")
		(6 "In2.Cu" signal "VCC")
		(8 "In3.Cu" signal "VCC1")
		(10 "In4.Cu" signal "GND1")
		(12 "In5.Cu" signal "IN1")
		(14 "In6.Cu" signal "GND2")
		(16 "In7.Cu" signal "IN2")
		(18 "In8.Cu" signal "GND3")
		(20 "In9.Cu" signal "IN3")
		(22 "In10.Cu" signal "GND4")
		(24 "In11.Cu" signal "IN4")
		(26 "In12.Cu" signal "GND5")
		(28 "In13.Cu" signal "IN5")
		(30 "In14.Cu" signal "GND6")
		(32 "In15.Cu" signal "IN6")
		(34 "In16.Cu" signal "GND7")
		(2 "B.Cu" signal "BOTTOM")
		(9 "F.Adhes" user "F.Adhesive")
		(11 "B.Adhes" user "B.Adhesive")
		(13 "F.Paste" user "Package Geometry/Pastemask Top")
		(15 "B.Paste" user "Package Geometry/Pastemask Bottom")
		(5 "F.SilkS" user "Ref Des/Silkscreen Top")
		(7 "B.SilkS" user "Ref Des/Silkscreen Bottom")
		(1 "F.Mask" user "Board Geometry/Soldermask Top")
		(3 "B.Mask" user "Board Geometry/Soldermask Bottom")
		(17 "Dwgs.User" user "User.Drawings")
		(19 "Cmts.User" user "User.Comments")
		(21 "Eco1.User" user "User.Eco1")
		(23 "Eco2.User" user "User.Eco2")
		(25 "Edge.Cuts" user "Board Geometry/Outline")
		(27 "Margin" user)
		(31 "F.CrtYd" user "Package Geometry/Place Bound Top")
		(29 "B.CrtYd" user "Package Geometry/Place Bound Bottom")
		(35 "F.Fab" user "Ref Des/Assembly Top")
		(33 "B.Fab" user "Ref Des/Assembly Bottom")
	)
	(footprint ""
		(layer "F.Cu")
		(at 312.739532 -138.661648 180)
		(property "Reference" "R294"
			(at 0 0 180)
			(layer "F.SilkS")
			(hide yes)
			(effects
				(font
					(size 1.27 1.27)
				)
			)
		)
		(property "Value" ""
			(at 0 0 180)
			(layer "F.Fab")
			(effects
				(font
					(size 1.27 1.27)
				)
			)
		)
		(duplicate_pad_numbers_are_jumpers no)
		(fp_line
			(start 0.7874 0.4064)
			(end -0.7874 0.4064)
			(stroke
				(width 0.1524)
				(type default)
			)
			(layer "F.SilkS")
		)
		(fp_line
			(start 0.7874 -0.4064)
			(end 0.7874 0.4064)
			(stroke
				(width 0.1524)
				(type default)
			)
			(layer "F.SilkS")
		)
		(fp_line
			(start -0.7874 0.4064)
			(end -0.7874 -0.4064)
			(stroke
				(width 0.1524)
				(type default)
			)
			(layer "F.SilkS")
		)
		(fp_line
			(start -0.7874 -0.4064)
			(end 0.7874 -0.4064)
			(stroke
				(width 0.1524)
				(type default)
			)
			(layer "F.SilkS")
		)
		(fp_line
			(start 0.67945 0.3048)
			(end 0.120396 0.3048)
			(stroke
				(width 0.1)
				(type default)
			)
			(layer "F.Fab")
		)
		(fp_line
			(start 0.67945 -0.3048)
			(end 0.67945 0.3048)
			(stroke
				(width 0.1)
				(type default)
			)
			(layer "F.Fab")
		)
		(fp_line
			(start 0.12065 -0.2794)
			(end 0.12065 -0.3048)
			(stroke
				(width 0.1)
				(type default)
			)
			(layer "F.Fab")
		)
		(fp_line
			(start 0.12065 -0.3048)
			(end 0.67945 -0.3048)
			(stroke
				(width 0.1)
				(type default)
			)
			(layer "F.Fab")
		)
		(fp_line
			(start 0.120396 0.3048)
			(end 0.120396 0.2794)
			(stroke
				(width 0.1)
				(type default)
			)
			(layer "F.Fab")
		)
		(fp_line
			(start 0.120396 0.2794)
			(end -0.12065 0.2794)
			(stroke
				(width 0.1)
				(type default)
			)
			(layer "F.Fab")
		)
		(fp_line
			(start -0.12065 0.3048)
			(end -0.67945 0.3048)
			(stroke
				(width 0.1)
				(type default)
			)
			(layer "F.Fab")
		)
		(fp_line
			(start -0.12065 0.2794)
			(end -0.12065 0.3048)
			(stroke
				(width 0.1)
				(type default)
			)
			(layer "F.Fab")
		)
		(fp_line
			(start -0.12065 -0.2794)
			(end 0.12065 -0.2794)
			(stroke
				(width 0.1)
				(type default)
			)
			(layer "F.Fab")
		)
		(fp_line
			(start -0.12065 -0.305054)
			(end -0.12065 -0.2794)
			(stroke
				(width 0.1)
				(type default)
			)
			(layer "F.Fab")
		)
		(fp_line
			(start -0.67945 0.3048)
			(end -0.67945 -0.305054)
			(stroke
				(width 0.1)
				(type default)
			)
			(layer "F.Fab")
		)
		(fp_line
			(start -0.67945 -0.305054)
			(end -0.12065 -0.305054)
			(stroke
				(width 0.1)
				(type default)
			)
			(layer "F.Fab")
		)
		(pad "1" smd circle
			(at -0.40005 0 180)
			(size 0 0)
			(layers "F.Cu" "F.Mask" "F.Paste")
			(net "PRSNT_NIC5_N")
		)
		(pad "2" smd circle
			(at 0.40005 0 180)
			(size 0 0)
			(layers "F.Cu" "F.Mask" "F.Paste")
			(net "PRSNTB0_NIC5_N")
		)
	)
	(footprint ""
		(layer "F.Cu")
		(at 343.567004 -356.244906 90)
		(property "Reference" "C581"
			(at 0 0 90)
			(layer "F.SilkS")
			(hide yes)
			(effects
				(font
					(size 1.27 1.27)
				)
			)
		)
		(property "Value" ""
			(at 0 0 90)
			(layer "F.Fab")
			(effects
				(font
					(size 1.27 1.27)
				)
			)
		)
		(duplicate_pad_numbers_are_jumpers no)
		(fp_line
			(start 0.299974 -0.150114)
			(end 0.299974 0.150114)
			(stroke
				(width 0.1)
				(type default)
			)
			(layer "F.Fab")
		)
		(fp_line
			(start -0.299974 -0.150114)
			(end 0.299974 -0.150114)
			(stroke
				(width 0.1)
				(type default)
			)
			(layer "F.Fab")
		)
		(fp_line
			(start 0.299974 0.150114)
			(end -0.299974 0.150114)
			(stroke
				(width 0.1)
				(type default)
			)
			(layer "F.Fab")
		)
		(fp_line
			(start -0.299974 0.150114)
			(end -0.299974 -0.150114)
			(stroke
				(width 0.1)
				(type default)
			)
			(layer "F.Fab")
		)
		(pad "1" smd rect
			(at -0.2667 0 90)
			(size 0.3048 0.381)
			(layers "F.Cu" "F.Mask" "F.Paste")
			(net "P5E_PEX2_STN6_TX_DP<96>")
		)
		(pad "2" smd rect
			(at 0.2667 0 90)
			(size 0.3048 0.381)
			(layers "F.Cu" "F.Mask" "F.Paste")
			(net "P5E_PEX2_STN6_TX_C_DP<96>")
		)
	)
	(footprint ""
		(layer "F.Cu")
		(at 172.401992 -343.952322 90)
		(property "Reference" "C2521"
			(at 0 0 90)
			(layer "F.SilkS")
			(hide yes)
			(effects
				(font
					(size 1.27 1.27)
				)
			)
		)
		(property "Value" ""
			(at 0 0 90)
			(layer "F.Fab")
			(effects
				(font
					(size 1.27 1.27)
				)
			)
		)
		(duplicate_pad_numbers_are_jumpers no)
		(fp_line
			(start 0.299974 -0.150114)
			(end 0.299974 0.150114)
			(stroke
				(width 0.1)
				(type default)
			)
			(layer "F.Fab")
		)
		(fp_line
			(start -0.299974 -0.150114)
			(end 0.299974 -0.150114)
			(stroke
				(width 0.1)
				(type default)
			)
			(layer "F.Fab")
		)
		(fp_line
			(start 0.299974 0.150114)
			(end -0.299974 0.150114)
			(stroke
				(width 0.1)
				(type default)
			)
			(layer "F.Fab")
		)
		(fp_line
			(start -0.299974 0.150114)
			(end -0.299974 -0.150114)
			(stroke
				(width 0.1)
				(type default)
			)
			(layer "F.Fab")
		)
		(pad "1" smd rect
			(at -0.2667 0 90)
			(size 0.3048 0.381)
			(layers "F.Cu" "F.Mask" "F.Paste")
			(net "P5E_PEX1_STN4_TX_DN<75>")
		)
		(pad "2" smd rect
			(at 0.2667 0 90)
			(size 0.3048 0.381)
			(layers "F.Cu" "F.Mask" "F.Paste")
			(net "P5E_PEX1_STN4_TX_C_DN<75>")
		)
	)
	(footprint ""
		(layer "F.Cu")
		(at 425.364402 -29.079952 180)
		(property "Reference" "R6212"
			(at 0 0 180)
			(layer "F.SilkS")
			(hide yes)
			(effects
				(font
					(size 1.27 1.27)
				)
			)
		)
		(property "Value" ""
			(at 0 0 180)
			(layer "F.Fab")
			(effects
				(font
					(size 1.27 1.27)
				)
			)
		)
		(duplicate_pad_numbers_are_jumpers no)
		(fp_line
			(start 0.7874 0.4064)
			(end -0.7874 0.4064)
			(stroke
				(width 0.1524)
				(type default)
			)
			(layer "F.SilkS")
		)
		(fp_line
			(start 0.7874 -0.4064)
			(end 0.7874 0.4064)
			(stroke
				(width 0.1524)
				(type default)
			)
			(layer "F.SilkS")
		)
		(fp_line
			(start -0.7874 0.4064)
			(end -0.7874 -0.4064)
			(stroke
				(width 0.1524)
				(type default)
			)
			(layer "F.SilkS")
		)
		(fp_line
			(start -0.7874 -0.4064)
			(end 0.7874 -0.4064)
			(stroke
				(width 0.1524)
				(type default)
			)
			(layer "F.SilkS")
		)
		(fp_line
			(start 0.67945 0.3048)
			(end 0.120396 0.3048)
			(stroke
				(width 0.1)
				(type default)
			)
			(layer "F.Fab")
		)
		(fp_line
			(start 0.67945 -0.3048)
			(end 0.67945 0.3048)
			(stroke
				(width 0.1)
				(type default)
			)
			(layer "F.Fab")
		)
		(fp_line
			(start 0.12065 -0.2794)
			(end 0.12065 -0.3048)
			(stroke
				(width 0.1)
				(type default)
			)
			(layer "F.Fab")
		)
		(fp_line
			(start 0.12065 -0.3048)
			(end 0.67945 -0.3048)
			(stroke
				(width 0.1)
				(type default)
			)
			(layer "F.Fab")
		)
		(fp_line
			(start 0.120396 0.3048)
			(end 0.120396 0.2794)
			(stroke
				(width 0.1)
				(type default)
			)
			(layer "F.Fab")
		)
		(fp_line
			(start 0.120396 0.2794)
			(end -0.12065 0.2794)
			(stroke
				(width 0.1)
				(type default)
			)
			(layer "F.Fab")
		)
		(fp_line
			(start -0.12065 0.3048)
			(end -0.67945 0.3048)
			(stroke
				(width 0.1)
				(type default)
			)
			(layer "F.Fab")
		)
		(fp_line
			(start -0.12065 0.2794)
			(end -0.12065 0.3048)
			(stroke
				(width 0.1)
				(type default)
			)
			(layer "F.Fab")
		)
		(fp_line
			(start -0.12065 -0.2794)
			(end 0.12065 -0.2794)
			(stroke
				(width 0.1)
				(type default)
			)
			(layer "F.Fab")
		)
		(fp_line
			(start -0.12065 -0.305054)
			(end -0.12065 -0.2794)
			(stroke
				(width 0.1)
				(type default)
			)
			(layer "F.Fab")
		)
		(fp_line
			(start -0.67945 0.3048)
			(end -0.67945 -0.305054)
			(stroke
				(width 0.1)
				(type default)
			)
			(layer "F.Fab")
		)
		(fp_line
			(start -0.67945 -0.305054)
			(end -0.12065 -0.305054)
			(stroke
				(width 0.1)
				(type default)
			)
			(layer "F.Fab")
		)
		(pad "1" smd circle
			(at -0.40005 0 180)
			(size 0 0)
			(layers "F.Cu" "F.Mask" "F.Paste")
			(net "GND")
		)
		(pad "2" smd circle
			(at 0.40005 0 180)
			(size 0 0)
			(layers "F.Cu" "F.Mask" "F.Paste")
			(net "SSD14_PWRDIS_R")
		)
	)
	(footprint ""
		(layer "F.Cu")
		(at 323.975222 -235.075222 90)
		(property "Reference" "R4387"
			(at 0 0 90)
			(layer "F.SilkS")
			(hide yes)
			(effects
				(font
					(size 1.27 1.27)
				)
			)
		)
		(property "Value" ""
			(at 0 0 90)
			(layer "F.Fab")
			(effects
				(font
					(size 1.27 1.27)
				)
			)
		)
		(duplicate_pad_numbers_are_jumpers no)
		(fp_line
			(start 0.7874 -0.4064)
			(end 0.7874 0.4064)
			(stroke
				(width 0.1524)
				(type default)
			)
			(layer "F.SilkS")
		)
		(fp_line
			(start -0.7874 -0.4064)
			(end 0.7874 -0.4064)
			(stroke
				(width 0.1524)
				(type default)
			)
			(layer "F.SilkS")
		)
		(fp_line
			(start 0.7874 0.4064)
			(end -0.7874 0.4064)
			(stroke
				(width 0.1524)
				(type default)
			)
			(layer "F.SilkS")
		)
		(fp_line
			(start -0.7874 0.4064)
			(end -0.7874 -0.4064)
			(stroke
				(width 0.1524)
				(type default)
			)
			(layer "F.SilkS")
		)
		(fp_line
			(start -0.12065 -0.305054)
			(end -0.12065 -0.2794)
			(stroke
				(width 0.1)
				(type default)
			)
			(layer "F.Fab")
		)
		(fp_line
			(start -0.67945 -0.305054)
			(end -0.12065 -0.305054)
			(stroke
				(width 0.1)
				(type default)
			)
			(layer "F.Fab")
		)
		(fp_line
			(start 0.67945 -0.3048)
			(end 0.67945 0.3048)
			(stroke
				(width 0.1)
				(type default)
			)
			(layer "F.Fab")
		)
		(fp_line
			(start 0.12065 -0.3048)
			(end 0.67945 -0.3048)
			(stroke
				(width 0.1)
				(type default)
			)
			(layer "F.Fab")
		)
		(fp_line
			(start 0.12065 -0.2794)
			(end 0.12065 -0.3048)
			(stroke
				(width 0.1)
				(type default)
			)
			(layer "F.Fab")
		)
		(fp_line
			(start -0.12065 -0.2794)
			(end 0.12065 -0.2794)
			(stroke
				(width 0.1)
				(type default)
			)
			(layer "F.Fab")
		)
		(fp_line
			(start 0.120396 0.2794)
			(end -0.12065 0.2794)
			(stroke
				(width 0.1)
				(type default)
			)
			(layer "F.Fab")
		)
		(fp_line
			(start -0.12065 0.2794)
			(end -0.12065 0.3048)
			(stroke
				(width 0.1)
				(type default)
			)
			(layer "F.Fab")
		)
		(fp_line
			(start 0.67945 0.3048)
			(end 0.120396 0.3048)
			(stroke
				(width 0.1)
				(type default)
			)
			(layer "F.Fab")
		)
		(fp_line
			(start 0.120396 0.3048)
			(end 0.120396 0.2794)
			(stroke
				(width 0.1)
				(type default)
			)
			(layer "F.Fab")
		)
		(fp_line
			(start -0.12065 0.3048)
			(end -0.67945 0.3048)
			(stroke
				(width 0.1)
				(type default)
			)
			(layer "F.Fab")
		)
		(fp_line
			(start -0.67945 0.3048)
			(end -0.67945 -0.305054)
			(stroke
				(width 0.1)
				(type default)
			)
			(layer "F.Fab")
		)
		(pad "1" smd circle
			(at -0.40005 0 90)
			(size 0 0)
			(layers "F.Cu" "F.Mask" "F.Paste")
			(net "RST_PEX_SYS_BUF_R_N")
		)
		(pad "2" smd circle
			(at 0.40005 0 90)
			(size 0 0)
			(layers "F.Cu" "F.Mask" "F.Paste")
			(net "RST_PEX0_SYS_N")
		)
	)
	(footprint ""
		(layer "F.Cu")
		(at 15.691866 -255.046734 -90)
		(property "Reference" "R6466"
			(at 0 0 270)
			(layer "F.SilkS")
			(hide yes)
			(effects
				(font
					(size 1.27 1.27)
				)
			)
		)
		(property "Value" ""
			(at 0 0 270)
			(layer "F.Fab")
			(effects
				(font
					(size 1.27 1.27)
				)
			)
		)
		(duplicate_pad_numbers_are_jumpers no)
		(fp_line
			(start -0.7874 0.4064)
			(end -0.7874 -0.4064)
			(stroke
				(width 0.1524)
				(type default)
			)
			(layer "F.SilkS")
		)
		(fp_line
			(start 0.7874 0.4064)
			(end -0.7874 0.4064)
			(stroke
				(width 0.1524)
				(type default)
			)
			(layer "F.SilkS")
		)
		(fp_line
			(start -0.7874 -0.4064)
			(end 0.7874 -0.4064)
			(stroke
				(width 0.1524)
				(type default)
			)
			(layer "F.SilkS")
		)
		(fp_line
			(start 0.7874 -0.4064)
			(end 0.7874 0.4064)
			(stroke
				(width 0.1524)
				(type default)
			)
			(layer "F.SilkS")
		)
		(fp_line
			(start -0.67945 0.3048)
			(end -0.67945 -0.305054)
			(stroke
				(width 0.1)
				(type default)
			)
			(layer "F.Fab")
		)
		(fp_line
			(start -0.12065 0.3048)
			(end -0.67945 0.3048)
			(stroke
				(width 0.1)
				(type default)
			)
			(layer "F.Fab")
		)
		(fp_line
			(start 0.120396 0.3048)
			(end 0.120396 0.2794)
			(stroke
				(width 0.1)
				(type default)
			)
			(layer "F.Fab")
		)
		(fp_line
			(start 0.67945 0.3048)
			(end 0.120396 0.3048)
			(stroke
				(width 0.1)
				(type default)
			)
			(layer "F.Fab")
		)
		(fp_line
			(start -0.12065 0.2794)
			(end -0.12065 0.3048)
			(stroke
				(width 0.1)
				(type default)
			)
			(layer "F.Fab")
		)
		(fp_line
			(start 0.120396 0.2794)
			(end -0.12065 0.2794)
			(stroke
				(width 0.1)
				(type default)
			)
			(layer "F.Fab")
		)
		(fp_line
			(start -0.12065 -0.2794)
			(end 0.12065 -0.2794)
			(stroke
				(width 0.1)
				(type default)
			)
			(layer "F.Fab")
		)
		(fp_line
			(start 0.12065 -0.2794)
			(end 0.12065 -0.3048)
			(stroke
				(width 0.1)
				(type default)
			)
			(layer "F.Fab")
		)
		(fp_line
			(start 0.12065 -0.3048)
			(end 0.67945 -0.3048)
			(stroke
				(width 0.1)
				(type default)
			)
			(layer "F.Fab")
		)
		(fp_line
			(start 0.67945 -0.3048)
			(end 0.67945 0.3048)
			(stroke
				(width 0.1)
				(type default)
			)
			(layer "F.Fab")
		)
		(fp_line
			(start -0.67945 -0.305054)
			(end -0.12065 -0.305054)
			(stroke
				(width 0.1)
				(type default)
			)
			(layer "F.Fab")
		)
		(fp_line
			(start -0.12065 -0.305054)
			(end -0.12065 -0.2794)
			(stroke
				(width 0.1)
				(type default)
			)
			(layer "F.Fab")
		)
		(pad "1" smd circle
			(at -0.40005 0 270)
			(size 0 0)
			(layers "F.Cu" "F.Mask" "F.Paste")
			(net "P1V25_SERDES_VDDPLL_PEX0")
		)
		(pad "2" smd circle
			(at 0.40005 0 270)
			(size 0 0)
			(layers "F.Cu" "F.Mask" "F.Paste")
			(net "P1V25_SERDES_VDDPLL_PEX0_C5")
		)
	)
	(footprint ""
		(layer "F.Cu")
		(at 285.66237 -22.937216 90)
		(property "Reference" "R1698"
			(at 0 0 90)
			(layer "F.SilkS")
			(hide yes)
			(effects
				(font
					(size 1.27 1.27)
				)
			)
		)
		(property "Value" ""
			(at 0 0 90)
			(layer "F.Fab")
			(effects
				(font
					(size 1.27 1.27)
				)
			)
		)
		(duplicate_pad_numbers_are_jumpers no)
		(fp_line
			(start 0.7874 -0.4064)
			(end 0.7874 0.4064)
			(stroke
				(width 0.1524)
				(type default)
			)
			(layer "F.SilkS")
		)
		(fp_line
			(start -0.7874 -0.4064)
			(end 0.7874 -0.4064)
			(stroke
				(width 0.1524)
				(type default)
			)
			(layer "F.SilkS")
		)
		(fp_line
			(start 0.7874 0.4064)
			(end -0.7874 0.4064)
			(stroke
				(width 0.1524)
				(type default)
			)
			(layer "F.SilkS")
		)
		(fp_line
			(start -0.7874 0.4064)
			(end -0.7874 -0.4064)
			(stroke
				(width 0.1524)
				(type default)
			)
			(layer "F.SilkS")
		)
		(fp_line
			(start -0.12065 -0.305054)
			(end -0.12065 -0.2794)
			(stroke
				(width 0.1)
				(type default)
			)
			(layer "F.Fab")
		)
		(fp_line
			(start -0.67945 -0.305054)
			(end -0.12065 -0.305054)
			(stroke
				(width 0.1)
				(type default)
			)
			(layer "F.Fab")
		)
		(fp_line
			(start 0.67945 -0.3048)
			(end 0.67945 0.3048)
			(stroke
				(width 0.1)
				(type default)
			)
			(layer "F.Fab")
		)
		(fp_line
			(start 0.12065 -0.3048)
			(end 0.67945 -0.3048)
			(stroke
				(width 0.1)
				(type default)
			)
			(layer "F.Fab")
		)
		(fp_line
			(start 0.12065 -0.2794)
			(end 0.12065 -0.3048)
			(stroke
				(width 0.1)
				(type default)
			)
			(layer "F.Fab")
		)
		(fp_line
			(start -0.12065 -0.2794)
			(end 0.12065 -0.2794)
			(stroke
				(width 0.1)
				(type default)
			)
			(layer "F.Fab")
		)
		(fp_line
			(start 0.120396 0.2794)
			(end -0.12065 0.2794)
			(stroke
				(width 0.1)
				(type default)
			)
			(layer "F.Fab")
		)
		(fp_line
			(start -0.12065 0.2794)
			(end -0.12065 0.3048)
			(stroke
				(width 0.1)
				(type default)
			)
			(layer "F.Fab")
		)
		(fp_line
			(start 0.67945 0.3048)
			(end 0.120396 0.3048)
			(stroke
				(width 0.1)
				(type default)
			)
			(layer "F.Fab")
		)
		(fp_line
			(start 0.120396 0.3048)
			(end 0.120396 0.2794)
			(stroke
				(width 0.1)
				(type default)
			)
			(layer "F.Fab")
		)
		(fp_line
			(start -0.12065 0.3048)
			(end -0.67945 0.3048)
			(stroke
				(width 0.1)
				(type default)
			)
			(layer "F.Fab")
		)
		(fp_line
			(start -0.67945 0.3048)
			(end -0.67945 -0.305054)
			(stroke
				(width 0.1)
				(type default)
			)
			(layer "F.Fab")
		)
		(pad "1" smd circle
			(at -0.40005 0 90)
			(size 0 0)
			(layers "F.Cu" "F.Mask" "F.Paste")
			(net "SMB_BIC_I2C9_MUX1_SSD9_R_SDA")
		)
		(pad "2" smd circle
			(at 0.40005 0 90)
			(size 0 0)
			(layers "F.Cu" "F.Mask" "F.Paste")
			(net "SMB_ISO_SSD9_SDA")
		)
	)
)
